(kicad_pcb
	(version 20241229)
	(generator "pcbnew")
	(generator_version "9.0")
	(general
		(thickness 1.62)
		(legacy_teardrops no)
	)
	(paper "A4")
	(title_block
		(title "OCuLink to 10GbE adapter")
		(date "2026-02-23")
		(rev "1.1.0")
		(company "Antmicro Ltd")
		(comment 1 "www.antmicro.com")
		(comment 9 "footprints 194-198 of 510")
	)
	(layers
		(0 "F.Cu" signal)
		(4 "In1.Cu" signal)
		(6 "In2.Cu" signal)
		(8 "In3.Cu" signal)
		(10 "In4.Cu" signal)
		(12 "In5.Cu" signal)
		(14 "In6.Cu" signal)
		(2 "B.Cu" signal)
		(9 "F.Adhes" user "F.Adhesive")
		(11 "B.Adhes" user "B.Adhesive")
		(13 "F.Paste" user)
		(15 "B.Paste" user)
		(5 "F.SilkS" user "F.Silkscreen")
		(7 "B.SilkS" user "B.Silkscreen")
		(1 "F.Mask" user)
		(3 "B.Mask" user)
		(17 "Dwgs.User" user "User.Drawings")
		(19 "Cmts.User" user "User.Comments")
		(21 "Eco1.User" user "User.Eco1")
		(23 "Eco2.User" user "User.Eco2")
		(25 "Edge.Cuts" user)
		(27 "Margin" user)
		(31 "F.CrtYd" user "F.Courtyard")
		(29 "B.CrtYd" user "B.Courtyard")
		(35 "F.Fab" user)
		(33 "B.Fab" user)
	)
	(footprint "antmicro-footprints:SOT-23-6"
		(layer "F.Cu")
		(at 86.35 66 180)
		(property "Reference" "U12"
			(at -1.61 0.21 90)
			(layer "F.SilkS")
			(effects
				(font
					(size 0.7 0.7)
					(thickness 0.15)
				)
				(justify right top)
			)
		)
		(property "Value" "LTC4412IS6"
			(at -1.749999 2.693 0)
			(layer "F.Fab")
			(hide yes)
			(effects
				(font
					(size 0.7 0.7)
					(thickness 0.15)
				)
				(justify right top)
			)
		)
		(property "Datasheet" "https://www.analog.com/media/en/technical-documentation/data-sheets/4412fb.pdf"
			(at 0 -0.057 0)
			(layer "F.Fab")
			(hide yes)
			(effects
				(font
					(size 1.27 1.27)
					(thickness 0.15)
				)
			)
		)
		(property "Description" "Ideal diode controller"
			(at 0 -0.057 0)
			(layer "F.Fab")
			(hide yes)
			(effects
				(font
					(size 1.27 1.27)
					(thickness 0.15)
				)
			)
		)
		(property "MPN" "LTC4412IS6#TRMPBF"
			(at 0 0 180)
			(unlocked yes)
			(layer "F.Fab")
			(hide yes)
			(effects
				(font
					(size 1 1)
					(thickness 0.15)
				)
			)
		)
		(property "Manufacturer" "Analog Devices"
			(at 0 0 180)
			(unlocked yes)
			(layer "F.Fab")
			(hide yes)
			(effects
				(font
					(size 1 1)
					(thickness 0.15)
				)
			)
		)
		(property "Author" "Antmicro"
			(at 0 0 180)
			(unlocked yes)
			(layer "F.Fab")
			(hide yes)
			(effects
				(font
					(size 1 1)
					(thickness 0.15)
				)
			)
		)
		(property "License" "Apache-2.0"
			(at 0 0 180)
			(unlocked yes)
			(layer "F.Fab")
			(hide yes)
			(effects
				(font
					(size 1 1)
					(thickness 0.15)
				)
			)
		)
		(sheetname "/Power/Ideal diode 2/")
		(sheetfile "ideal-diode.kicad_sch")
		(attr smd)
		(fp_line
			(start 1.45 0.643)
			(end 1.45 0.343)
			(stroke
				(width 0.12)
				(type solid)
			)
			(layer "F.SilkS")
		)
		(fp_line
			(start 1.45 -0.757)
			(end 1.45 -0.457)
			(stroke
				(width 0.12)
				(type solid)
			)
			(layer "F.SilkS")
		)
		(fp_line
			(start 1.3 0.643)
			(end 1.45 0.643)
			(stroke
				(width 0.12)
				(type solid)
			)
			(layer "F.SilkS")
		)
		(fp_line
			(start 1.3 -0.757)
			(end 1.45 -0.757)
			(stroke
				(width 0.12)
				(type solid)
			)
			(layer "F.SilkS")
		)
		(fp_line
			(start -1.3 -0.757)
			(end -1.45 -0.757)
			(stroke
				(width 0.12)
				(type solid)
			)
			(layer "F.SilkS")
		)
		(fp_line
			(start -1.45 0.643)
			(end -1.45 0.343)
			(stroke
				(width 0.12)
				(type solid)
			)
			(layer "F.SilkS")
		)
		(fp_line
			(start -1.45 -0.757)
			(end -1.45 -0.457)
			(stroke
				(width 0.12)
				(type solid)
			)
			(layer "F.SilkS")
		)
		(fp_rect
			(start -1.55 -1.85)
			(end 1.55 1.75)
			(stroke
				(width 0.05)
				(type solid)
			)
			(fill no)
			(layer "F.CrtYd")
		)
		(fp_line
			(start 1.5 0.643)
			(end -1.5 0.643)
			(stroke
				(width 0.1)
				(type solid)
			)
			(layer "F.Fab")
		)
		(fp_line
			(start 1.5 -0.757)
			(end 1.5 0.643)
			(stroke
				(width 0.1)
				(type solid)
			)
			(layer "F.Fab")
		)
		(fp_line
			(start -1.5 0.643)
			(end -1.5 -0.757)
			(stroke
				(width 0.1)
				(type solid)
			)
			(layer "F.Fab")
		)
		(fp_line
			(start -1.5 -0.757)
			(end 1.5 -0.757)
			(stroke
				(width 0.1)
				(type solid)
			)
			(layer "F.Fab")
		)
		(fp_text user "."
			(at -1.4 1.46 0)
			(layer "F.SilkS")
			(effects
				(font
					(size 1 1)
					(thickness 0.15)
				)
			)
		)
		(pad "1" smd roundrect
			(at -0.954 1.1 180)
			(size 0.55 1)
			(layers "F.Cu" "F.Mask" "F.Paste")
			(roundrect_rratio 0.15)
			(net 351 "/Power/+5V_USB")
			(pinfunction "IN")
			(pintype "power_in")
		)
		(pad "2" smd roundrect
			(at -0.003 1.1 180)
			(size 0.55 1)
			(layers "F.Cu" "F.Mask" "F.Paste")
			(roundrect_rratio 0.15)
			(net 28 "GND")
			(pinfunction "GND")
			(pintype "power_in")
		)
		(pad "3" smd roundrect
			(at 0.947 1.1 180)
			(size 0.55 1)
			(layers "F.Cu" "F.Mask" "F.Paste")
			(roundrect_rratio 0.15)
			(net 28 "GND")
			(pinfunction "CTL")
			(pintype "input")
		)
		(pad "4" smd roundrect
			(at 0.947 -1.214 180)
			(size 0.55 1)
			(layers "F.Cu" "F.Mask" "F.Paste")
			(roundrect_rratio 0.15)
			(net 375 "unconnected-(U12-STAT-Pad4)")
			(pinfunction "STAT")
			(pintype "output+no_connect")
		)
		(pad "5" smd roundrect
			(at -0.003 -1.214 180)
			(size 0.55 1)
			(layers "F.Cu" "F.Mask" "F.Paste")
			(roundrect_rratio 0.15)
			(net 156 "Net-(Q3-G)")
			(pinfunction "GATE")
			(pintype "output")
		)
		(pad "6" smd roundrect
			(at -0.954 -1.214 180)
			(size 0.55 1)
			(layers "F.Cu" "F.Mask" "F.Paste")
			(roundrect_rratio 0.15)
			(net 314 "VCC")
			(pinfunction "SENSE")
			(pintype "input")
		)
	)
	(footprint "antmicro-footprints:C_0402_1005Metric"
		(layer "F.Cu")
		(at 105.7 112.5)
		(descr "Capacitor SMD 0402")
		(tags "capacitor SMD 0402")
		(property "Reference" "C70"
			(at 0.83 1.45 0)
			(layer "F.SilkS")
			(effects
				(font
					(size 0.7 0.7)
					(thickness 0.15)
				)
				(justify left bottom)
			)
		)
		(property "Value" "C_100n_0402"
			(at -1.022927 2.155213 0)
			(layer "F.Fab")
			(hide yes)
			(effects
				(font
					(size 0.7 0.7)
					(thickness 0.15)
				)
				(justify left bottom)
			)
		)
		(property "Datasheet" "https://www.murata.com/products/productdetail?partno=GRM155R61H104KE14%23"
			(at 0 0 0)
			(layer "F.Fab")
			(hide yes)
			(effects
				(font
					(size 1.27 1.27)
					(thickness 0.15)
				)
			)
		)
		(property "Description" "SMD Multilayer Ceramic Capacitor, 0.1 µF, 50 V, 0402 [1005 Metric], ± 10%, X5R, GRM Series"
			(at 0 0 0)
			(layer "F.Fab")
			(hide yes)
			(effects
				(font
					(size 1.27 1.27)
					(thickness 0.15)
				)
			)
		)
		(property "MPN" "GRM155R61H104KE14D"
			(at 0 0 0)
			(unlocked yes)
			(layer "F.Fab")
			(hide yes)
			(effects
				(font
					(size 1 1)
					(thickness 0.15)
				)
			)
		)
		(property "Val" "100n"
			(at 0 0 0)
			(unlocked yes)
			(layer "F.Fab")
			(hide yes)
			(effects
				(font
					(size 1 1)
					(thickness 0.15)
				)
			)
		)
		(property "Voltage" "50V"
			(at 0 0 0)
			(unlocked yes)
			(layer "F.Fab")
			(hide yes)
			(effects
				(font
					(size 1 1)
					(thickness 0.15)
				)
			)
		)
		(property "Dielectric" "X5R"
			(at 0 0 0)
			(unlocked yes)
			(layer "F.Fab")
			(hide yes)
			(effects
				(font
					(size 1 1)
					(thickness 0.15)
				)
			)
		)
		(property "Manufacturer" "Murata"
			(at 0 0 0)
			(unlocked yes)
			(layer "F.Fab")
			(hide yes)
			(effects
				(font
					(size 1 1)
					(thickness 0.15)
				)
			)
		)
		(property "License" "Apache-2.0"
			(at 0 0 0)
			(unlocked yes)
			(layer "F.Fab")
			(hide yes)
			(effects
				(font
					(size 1 1)
					(thickness 0.15)
				)
			)
		)
		(property "Author" "Antmicro"
			(at 0 0 0)
			(unlocked yes)
			(layer "F.Fab")
			(hide yes)
			(effects
				(font
					(size 1 1)
					(thickness 0.15)
				)
			)
		)
		(sheetname "/X710-AT2 10GbE/")
		(sheetfile "x710-at2-10gbe.kicad_sch")
		(attr smd)
		(fp_rect
			(start -0.925 -0.47)
			(end 0.925 0.47)
			(stroke
				(width 0.05)
				(type default)
			)
			(fill no)
			(layer "F.CrtYd")
		)
		(fp_line
			(start -0.494 -0.25)
			(end 0.504 -0.25)
			(stroke
				(width 0.15)
				(type solid)
			)
			(layer "F.Fab")
		)
		(fp_line
			(start -0.494 0.248)
			(end -0.494 -0.25)
			(stroke
				(width 0.15)
				(type solid)
			)
			(layer "F.Fab")
		)
		(fp_line
			(start 0.504 -0.25)
			(end 0.504 0.248)
			(stroke
				(width 0.15)
				(type solid)
			)
			(layer "F.Fab")
		)
		(fp_line
			(start 0.504 0.248)
			(end -0.494 0.248)
			(stroke
				(width 0.15)
				(type solid)
			)
			(layer "F.Fab")
		)
		(pad "1" smd roundrect
			(at -0.48 0)
			(size 0.59 0.64)
			(layers "F.Cu" "F.Mask" "F.Paste")
			(roundrect_rratio 0.25)
			(net 28 "GND")
			(pintype "passive")
		)
		(pad "2" smd roundrect
			(at 0.48 0)
			(size 0.59 0.64)
			(layers "F.Cu" "F.Mask" "F.Paste")
			(roundrect_rratio 0.25)
			(net 7 "+3V3")
			(pintype "passive")
		)
	)
	(footprint "antmicro-footprints:C_0603_1608Metric_EIA"
		(layer "F.Cu")
		(at 60.649999 85.450002)
		(descr "Capacitor SMD 0603, IPC-7351 Density Level A")
		(tags "Capacitor 0603")
		(property "Reference" "C204"
			(at -1.429999 -1.990002 0)
			(layer "F.SilkS")
			(effects
				(font
					(size 0.7 0.7)
					(thickness 0.15)
				)
				(justify left bottom)
			)
		)
		(property "Value" "C_22u_16V_0603"
			(at -1.42757 1.770288 0)
			(layer "F.Fab")
			(hide yes)
			(effects
				(font
					(size 0.7 0.7)
					(thickness 0.15)
				)
				(justify left bottom)
			)
		)
		(property "Datasheet" "https://product.samsungsem.com/mlcc/CL10A226MO7JZN.do"
			(at 0 0 0)
			(layer "F.Fab")
			(hide yes)
			(effects
				(font
					(size 1.27 1.27)
					(thickness 0.15)
				)
			)
		)
		(property "Description" "SMD Multilayer Ceramic Capacitor"
			(at 0 0 0)
			(layer "F.Fab")
			(hide yes)
			(effects
				(font
					(size 1.27 1.27)
					(thickness 0.15)
				)
			)
		)
		(property "MPN" "CL10A226MO7JZNC"
			(at 0 0 0)
			(unlocked yes)
			(layer "F.Fab")
			(hide yes)
			(effects
				(font
					(size 1 1)
					(thickness 0.15)
				)
			)
		)
		(property "Manufacturer" "Samsung Electro-Mechanics"
			(at 0 0 0)
			(unlocked yes)
			(layer "F.Fab")
			(hide yes)
			(effects
				(font
					(size 1 1)
					(thickness 0.15)
				)
			)
		)
		(property "License" "Apache-2.0"
			(at 0 0 0)
			(unlocked yes)
			(layer "F.Fab")
			(hide yes)
			(effects
				(font
					(size 1 1)
					(thickness 0.15)
				)
			)
		)
		(property "Author" "Antmicro"
			(at 0 0 0)
			(unlocked yes)
			(layer "F.Fab")
			(hide yes)
			(effects
				(font
					(size 1 1)
					(thickness 0.15)
				)
			)
		)
		(property "Val" "22u"
			(at 0 0 0)
			(unlocked yes)
			(layer "F.Fab")
			(hide yes)
			(effects
				(font
					(size 1 1)
					(thickness 0.15)
				)
			)
		)
		(property "Voltage" "16V"
			(at 0 0 0)
			(unlocked yes)
			(layer "F.Fab")
			(hide yes)
			(effects
				(font
					(size 1 1)
					(thickness 0.15)
				)
			)
		)
		(property "Dielectric" ""
			(at 0 0 0)
			(unlocked yes)
			(layer "F.Fab")
			(hide yes)
			(effects
				(font
					(size 1 1)
					(thickness 0.15)
				)
			)
		)
		(property "Public" "False"
			(at 0 0 0)
			(unlocked yes)
			(layer "F.Fab")
			(hide yes)
			(effects
				(font
					(size 1 1)
					(thickness 0.15)
				)
			)
		)
		(sheetname "/Power/")
		(sheetfile "power.kicad_sch")
		(attr smd)
		(fp_line
			(start -0.15 -0.55)
			(end 0.15 -0.55)
			(stroke
				(width 0.15)
				(type solid)
			)
			(layer "F.SilkS")
		)
		(fp_line
			(start -0.15 0.55)
			(end 0.15 0.55)
			(stroke
				(width 0.15)
				(type solid)
			)
			(layer "F.SilkS")
		)
		(fp_rect
			(start -1.25 -0.65)
			(end 1.25 0.65)
			(stroke
				(width 0.05)
				(type solid)
			)
			(fill no)
			(layer "F.CrtYd")
		)
		(fp_rect
			(start -0.8 -0.45)
			(end 0.8 0.45)
			(stroke
				(width 0.15)
				(type solid)
			)
			(fill no)
			(layer "F.Fab")
		)
		(pad "1" smd roundrect
			(at -0.7 0)
			(size 0.8 1.1)
			(layers "F.Cu" "F.Mask" "F.Paste")
			(roundrect_rratio 0.2)
			(net 28 "GND")
			(pintype "passive")
		)
		(pad "2" smd roundrect
			(at 0.7 0)
			(size 0.8 1.1)
			(layers "F.Cu" "F.Mask" "F.Paste")
			(roundrect_rratio 0.2)
			(net 303 "/Power/+VCCD_OUT")
			(pintype "passive")
		)
	)
	(footprint "antmicro-footprints:R_0402_1005Metric"
		(layer "F.Cu")
		(at 109.15 100.1 -90)
		(descr "Resistor SMD 0402")
		(tags "resistor SMD 0402")
		(property "Reference" "R182"
			(at -0.8 -0.45 90)
			(layer "F.SilkS")
			(effects
				(font
					(size 0.7 0.7)
					(thickness 0.15)
				)
				(justify left bottom)
			)
		)
		(property "Value" "R_6k04_0.1%_0402"
			(at -1.011843 1.772046 90)
			(layer "F.Fab")
			(hide yes)
			(effects
				(font
					(size 0.7 0.7)
					(thickness 0.15)
				)
				(justify right top)
			)
		)
		(property "Datasheet" "https://www.vishay.com/docs/28758/tnpw_e3.pdf"
			(at 0 0 90)
			(layer "F.Fab")
			(hide yes)
			(effects
				(font
					(size 1.27 1.27)
					(thickness 0.15)
				)
			)
		)
		(property "Description" "SMD Chip Resistor, 6.49 kohm, ± 1%, 62.5 mW, 0402 [1005 Metric], Thick Film, General Purpose"
			(at 0 0 90)
			(layer "F.Fab")
			(hide yes)
			(effects
				(font
					(size 1.27 1.27)
					(thickness 0.15)
				)
			)
		)
		(property "MPN" "TNPW04026K04BEED"
			(at 0 0 270)
			(unlocked yes)
			(layer "F.Fab")
			(hide yes)
			(effects
				(font
					(size 1 1)
					(thickness 0.15)
				)
			)
		)
		(property "Manufacturer" "Vishay"
			(at 0 0 270)
			(unlocked yes)
			(layer "F.Fab")
			(hide yes)
			(effects
				(font
					(size 1 1)
					(thickness 0.15)
				)
			)
		)
		(property "License" "Apache-2.0"
			(at 0 0 270)
			(unlocked yes)
			(layer "F.Fab")
			(hide yes)
			(effects
				(font
					(size 1 1)
					(thickness 0.15)
				)
			)
		)
		(property "Author" "Antmicro"
			(at 0 0 270)
			(unlocked yes)
			(layer "F.Fab")
			(hide yes)
			(effects
				(font
					(size 1 1)
					(thickness 0.15)
				)
			)
		)
		(property "Val" "6k04"
			(at 0 0 270)
			(unlocked yes)
			(layer "F.Fab")
			(hide yes)
			(effects
				(font
					(size 1 1)
					(thickness 0.15)
				)
			)
		)
		(property "Tolerance" "0.1%"
			(at 0 0 270)
			(unlocked yes)
			(layer "F.Fab")
			(hide yes)
			(effects
				(font
					(size 1 1)
					(thickness 0.15)
				)
			)
		)
		(sheetname "/Fan controller/")
		(sheetfile "fan-controller.kicad_sch")
		(attr smd exclude_from_pos_files exclude_from_bom dnp)
		(fp_rect
			(start -0.925 -0.47)
			(end 0.925 0.47)
			(stroke
				(width 0.05)
				(type default)
			)
			(fill no)
			(layer "F.CrtYd")
		)
		(fp_rect
			(start -0.5 -0.25)
			(end 0.5 0.25)
			(stroke
				(width 0.15)
				(type solid)
			)
			(fill no)
			(layer "F.Fab")
		)
		(pad "1" smd roundrect
			(at -0.48 0 270)
			(size 0.59 0.64)
			(layers "F.Cu" "F.Mask" "F.Paste")
			(roundrect_rratio 0.25)
			(net 397 "Net-(R175-Pad1)")
			(pintype "passive")
		)
		(pad "2" smd roundrect
			(at 0.48 0 270)
			(size 0.59 0.64)
			(layers "F.Cu" "F.Mask" "F.Paste")
			(roundrect_rratio 0.25)
			(net 388 "/Fan controller/+5V")
			(pintype "passive")
		)
	)
	(footprint "antmicro-footprints:C_0402_1005Metric"
		(layer "F.Cu")
		(at 82.25 84.15)
		(descr "Capacitor SMD 0402")
		(tags "capacitor SMD 0402")
		(property "Reference" "C198"
			(at 0.8 0.5 0)
			(layer "F.SilkS")
			(effects
				(font
					(size 0.7 0.7)
					(thickness 0.15)
				)
				(justify left bottom)
			)
		)
		(property "Value" "C_100n_0402"
			(at -1.022927 2.155213 0)
			(layer "F.Fab")
			(hide yes)
			(effects
				(font
					(size 0.7 0.7)
					(thickness 0.15)
				)
				(justify left bottom)
			)
		)
		(property "Datasheet" "https://www.murata.com/products/productdetail?partno=GRM155R61H104KE14%23"
			(at 0 0 0)
			(layer "F.Fab")
			(hide yes)
			(effects
				(font
					(size 1.27 1.27)
					(thickness 0.15)
				)
			)
		)
		(property "Description" "SMD Multilayer Ceramic Capacitor, 0.1 µF, 50 V, 0402 [1005 Metric], ± 10%, X5R, GRM Series"
			(at 0 0 0)
			(layer "F.Fab")
			(hide yes)
			(effects
				(font
					(size 1.27 1.27)
					(thickness 0.15)
				)
			)
		)
		(property "MPN" "GRM155R61H104KE14D"
			(at 0 0 0)
			(unlocked yes)
			(layer "F.Fab")
			(hide yes)
			(effects
				(font
					(size 1 1)
					(thickness 0.15)
				)
			)
		)
		(property "Val" "100n"
			(at 0 0 0)
			(unlocked yes)
			(layer "F.Fab")
			(hide yes)
			(effects
				(font
					(size 1 1)
					(thickness 0.15)
				)
			)
		)
		(property "Voltage" "50V"
			(at 0 0 0)
			(unlocked yes)
			(layer "F.Fab")
			(hide yes)
			(effects
				(font
					(size 1 1)
					(thickness 0.15)
				)
			)
		)
		(property "Dielectric" "X5R"
			(at 0 0 0)
			(unlocked yes)
			(layer "F.Fab")
			(hide yes)
			(effects
				(font
					(size 1 1)
					(thickness 0.15)
				)
			)
		)
		(property "Manufacturer" "Murata"
			(at 0 0 0)
			(unlocked yes)
			(layer "F.Fab")
			(hide yes)
			(effects
				(font
					(size 1 1)
					(thickness 0.15)
				)
			)
		)
		(property "License" "Apache-2.0"
			(at 0 0 0)
			(unlocked yes)
			(layer "F.Fab")
			(hide yes)
			(effects
				(font
					(size 1 1)
					(thickness 0.15)
				)
			)
		)
		(property "Author" "Antmicro"
			(at 0 0 0)
			(unlocked yes)
			(layer "F.Fab")
			(hide yes)
			(effects
				(font
					(size 1 1)
					(thickness 0.15)
				)
			)
		)
		(sheetname "/X710-AT2 Misc/")
		(sheetfile "x710-at2-mics.kicad_sch")
		(attr smd)
		(fp_rect
			(start -0.925 -0.47)
			(end 0.925 0.47)
			(stroke
				(width 0.05)
				(type default)
			)
			(fill no)
			(layer "F.CrtYd")
		)
		(fp_line
			(start -0.494 -0.25)
			(end 0.504 -0.25)
			(stroke
				(width 0.15)
				(type solid)
			)
			(layer "F.Fab")
		)
		(fp_line
			(start -0.494 0.248)
			(end -0.494 -0.25)
			(stroke
				(width 0.15)
				(type solid)
			)
			(layer "F.Fab")
		)
		(fp_line
			(start 0.504 -0.25)
			(end 0.504 0.248)
			(stroke
				(width 0.15)
				(type solid)
			)
			(layer "F.Fab")
		)
		(fp_line
			(start 0.504 0.248)
			(end -0.494 0.248)
			(stroke
				(width 0.15)
				(type solid)
			)
			(layer "F.Fab")
		)
		(pad "1" smd roundrect
			(at -0.48 0)
			(size 0.59 0.64)
			(layers "F.Cu" "F.Mask" "F.Paste")
			(roundrect_rratio 0.25)
			(net 28 "GND")
			(pintype "passive")
		)
		(pad "2" smd roundrect
			(at 0.48 0)
			(size 0.59 0.64)
			(layers "F.Cu" "F.Mask" "F.Paste")
			(roundrect_rratio 0.25)
			(net 78 "Net-(U10-VCC)")
			(pintype "passive")
		)
	)
)
